# T6G (Grand Teton) — schematic netlist excerpt (pin names and nets, part order shuffled) for the footprints in the layout excerpt that follows; sources: Cadence DE-HDL packaged netlist, KiCad conversion of 04192023_DAF0TMB3IC0_F0TG_MB_C_brd_V02_OCP.brd

J28  SCONN288_DDR506112002KQ  IO  pkg DDR288S_1-1VXC  page 100
  VIN_BULK0  = P12V_MEM_CPU1
  RFU0  = NC
  VIN_MGMT  = P3V3_AUX
  HSCL  = I3C_SPD_DDRC_CPU1_SCL
  HSDA  = I3C_SPD_DDRC_CPU1_SDA
  VSS0  = GND
  DQ0_A  = M_C_CPU1_SA_DQ<0>
  VSS1  = GND
  DQ1_A  = M_C_CPU1_SA_DQ<1>
  VSS2  = GND
  DQS0_A_T  = M_C_CPU1_SA_DQS_DP<0>
  DQS0_A_C  = M_C_CPU1_SA_DQS_DN<0>
  VSS3  = GND
  DQ4_A  = M_C_CPU1_SA_DQ<4>
  VSS4  = GND
  DQ5_A  = M_C_CPU1_SA_DQ<5>
  VSS5  = GND
  DQ8_A  = M_C_CPU1_SA_DQ<8>
  VSS6  = GND
  DQ9_A  = M_C_CPU1_SA_DQ<9>
  VSS7  = GND
  DQS1_A_T  = M_C_CPU1_SA_DQS_DP<1>
  DQS1_A_C  = M_C_CPU1_SA_DQS_DN<1>
  VSS8  = GND
  DQ12_A  = M_C_CPU1_SA_DQ<12>
  VSS9  = GND
  DQ13_A  = M_C_CPU1_SA_DQ<13>
  VSS10  = GND
  DQ16_A  = M_C_CPU1_SA_DQ<16>
  VSS11  = GND
  DQ17_A  = M_C_CPU1_SA_DQ<17>
  VSS12  = GND
  DQS2_A_T  = M_C_CPU1_SA_DQS_DP<2>
  DQS2_A_C  = M_C_CPU1_SA_DQS_DN<2>
  VSS13  = GND
  DQ20_A  = M_C_CPU1_SA_DQ<20>
  VSS14  = GND
  DQ21_A  = M_C_CPU1_SA_DQ<21>
  VSS15  = GND
  DQ24_A  = M_C_CPU1_SA_DQ<24>
  VSS16  = GND
  DQ25_A  = M_C_CPU1_SA_DQ<25>
  VSS17  = GND
  DQS3_A_T  = M_C_CPU1_SA_DQS_DP<3>
  DQS3_A_C  = M_C_CPU1_SA_DQS_DN<3>
  VSS18  = GND
  DQ28_A  = M_C_CPU1_SA_DQ<28>
  VSS19  = GND
  DQ29_A  = M_C_CPU1_SA_DQ<29>
  VSS20  = GND
  CB0_A  = M_C_CPU1_SA_CB<0>
  VSS21  = GND
  CB1_A  = M_C_CPU1_SA_CB<1>
  VSS22  = GND
  DQS4_A_T  = M_C_CPU1_SA_DQS_DP<4>
  DQS4_A_C  = M_C_CPU1_SA_DQS_DN<4>
  VSS23  = GND
  CB4_A  = M_C_CPU1_SA_CB<4>
  VSS24  = GND
  CB5_A  = M_C_CPU1_SA_CB<5>
  VSS25  = GND
  ALERT_N  = M_C_CPU1_ALERT_N
  VSS26  = GND
  CS0_A_N  = M_C_CPU1_SA_CS_N<0>
  VSS27  = GND
  CA0_A  = M_C_CPU1_SA_CA<0>
  VSS28  = GND
  CA2_A  = M_C_CPU1_SA_CA<2>
  VSS29  = GND
  CA4_A  = M_C_CPU1_SA_CA<4>
  VSS30  = GND
  CA6_A  = M_C_CPU1_SA_CA<6>
  VSS31  = GND
  PAR_A  = M_C_CPU1_SA_PAR
  VSS32  = GND
  CA0_B  = M_C_CPU1_SB_CA<0>
  VSS33  = GND
  CA2_B  = M_C_CPU1_SB_CA<2>
  VSS34  = GND
  CA4_B  = M_C_CPU1_SB_CA<4>
  VSS35  = GND
  CA6_B  = M_C_CPU1_SB_CA<6>
  VSS36  = GND
  CS0_B_N  = M_C_CPU1_SB_CS_N<0>
  VSS37  = GND
  \lbd||rsp_a_n\  = M_C_CPU1_SA_RSP<0>
  \lbs||rsp_b_n\  = M_C_CPU1_SB_RSP<0>
  VSS38  = GND
  CB4_B  = M_C_CPU1_SB_CB<4>
  VSS39  = GND
  CB5_B  = M_C_CPU1_SB_CB<5>
  VSS40  = GND
  \dqs9_b_t||tdqs9_b_t||dbi4_b_n\  = M_C_CPU1_SB_DQS_DP<9>
  \dqs9_b_c||tdqs9_b_c\  = M_C_CPU1_SB_DQS_DN<9>
  VSS41  = GND
  CB0_B  = M_C_CPU1_SB_CB<0>
  VSS42  = GND
  CB1_B  = M_C_CPU1_SB_CB<1>
  VSS43  = GND
  DQ0_B  = M_C_CPU1_SB_DQ<0>
  VSS44  = GND
  DQ1_B  = M_C_CPU1_SB_DQ<1>
  VSS45  = GND
  DQS0_B_T  = M_C_CPU1_SB_DQS_DP<0>
  DQS0_B_C  = M_C_CPU1_SB_DQS_DN<0>
  VSS46  = GND
  DQ4_B  = M_C_CPU1_SB_DQ<4>
  VSS47  = GND
  DQ5_B  = M_C_CPU1_SB_DQ<5>
  VSS48  = GND
  DQ8_B  = M_C_CPU1_SB_DQ<8>
  VSS49  = GND
  DQ9_B  = M_C_CPU1_SB_DQ<9>
  VSS50  = GND
  DQS1_B_T  = M_C_CPU1_SB_DQS_DP<1>
  DQS1_B_C  = M_C_CPU1_SB_DQS_DN<1>
  VSS51  = GND
  DQ12_B  = M_C_CPU1_SB_DQ<12>
  VSS52  = GND
  DQ13_B  = M_C_CPU1_SB_DQ<13>
  VSS53  = GND
  DQ16_B  = M_C_CPU1_SB_DQ<16>
  VSS54  = GND
  DQ17_B  = M_C_CPU1_SB_DQ<17>
  VSS55  = GND
  DQS2_B_T  = M_C_CPU1_SB_DQS_DP<2>
  DQS2_B_C  = M_C_CPU1_SB_DQS_DN<2>
  VSS56  = GND
  DQ20_B  = M_C_CPU1_SB_DQ<20>
  VSS57  = GND
  DQ21_B  = M_C_CPU1_SB_DQ<21>
  VSS58  = GND
  DQ24_B  = M_C_CPU1_SB_DQ<24>
  VSS59  = GND
  DQ25_B  = M_C_CPU1_SB_DQ<25>
  VSS60  = GND
  DQS3_B_T  = M_C_CPU1_SB_DQS_DP<3>
  DQS3_B_C  = M_C_CPU1_SB_DQS_DN<3>
  VSS61  = GND
  DQ28_B  = M_C_CPU1_SB_DQ<28>
  VSS62  = GND
  DQ29_B  = M_C_CPU1_SB_DQ<29>
  VSS63  = GND
  RFU1  = NC
  VIN_BULK1  = P12V_MEM_CPU1
  VIN_BULK2  = P12V_MEM_CPU1
  \pwr_good||fail_n\  = PWRGD_CHC_CPU1_DIMM
  HAS  = PD_CHC_CPU1_DIMM_SAA
  RFU2  = NC
  RFU3  = NC
  VSS64  = GND
  DQ2_A  = M_C_CPU1_SA_DQ<2>
  VSS65  = GND
  DQ3_A  = M_C_CPU1_SA_DQ<3>
  VSS66  = GND
  \dqs5_a_c||tdqs5_a_c||dqs5_a_t||tdqs5_a_t\  = M_C_CPU1_SA_DQS_DN<5>
  \dqs5_a_t||tdqs5_a_t\  = M_C_CPU1_SA_DQS_DP<5>
  VSS67  = GND
  DQ6_A  = M_C_CPU1_SA_DQ<6>
  VSS68  = GND
  DQ7_A  = M_C_CPU1_SA_DQ<7>
  VSS69  = GND
  DQ10_A  = M_C_CPU1_SA_DQ<10>
  VSS70  = GND
  DQ11_A  = M_C_CPU1_SA_DQ<11>
  VSS71  = GND
  \dqs6_a_c||tdqs6_a_c||dqs6_a_t||tdqs6_a_t\  = M_C_CPU1_SA_DQS_DN<6>
  \dqs6_a_t||tdqs6_a_t\  = M_C_CPU1_SA_DQS_DP<6>
  VSS72  = GND
  DQ14_A  = M_C_CPU1_SA_DQ<14>
  VSS73  = GND
  DQ15_A  = M_C_CPU1_SA_DQ<15>
  VSS74  = GND
  DQ18_A  = M_C_CPU1_SA_DQ<18>
  VSS75  = GND
  DQ19_A  = M_C_CPU1_SA_DQ<19>
  VSS76  = GND
  \dqs7_a_c||tdqs7_a_c\  = M_C_CPU1_SA_DQS_DN<7>
  \dqs7_a_t||tdqs7_a_t\  = M_C_CPU1_SA_DQS_DP<7>
  VSS77  = GND
  DQ22_A  = M_C_CPU1_SA_DQ<22>
  VSS78  = GND
  DQ23_A  = M_C_CPU1_SA_DQ<23>
  VSS79  = GND
  DQ26_A  = M_C_CPU1_SA_DQ<26>
  VSS80  = GND
  DQ27_A  = M_C_CPU1_SA_DQ<27>
  VSS81  = GND
  \dqs8_a_c||tdqs8_a_c\  = M_C_CPU1_SA_DQS_DN<8>
  \dqs8_a_t||tdqs8_a_t\  = M_C_CPU1_SA_DQS_DP<8>
  VSS82  = GND
  DQ30_A  = M_C_CPU1_SA_DQ<30>
  VSS83  = GND
  DQ31_A  = M_C_CPU1_SA_DQ<31>
  VSS84  = GND
  CB2_A  = M_C_CPU1_SA_CB<2>
  VSS85  = GND
  CB3_A  = M_C_CPU1_SA_CB<3>
  VSS86  = GND
  \dqs9_a_c||tdqs9_a_c\  = M_C_CPU1_SA_DQS_DN<9>
  \dqs9_a_t||tdqs9_a_t\  = M_C_CPU1_SA_DQS_DP<9>
  VSS87  = GND
  CB6_A  = M_C_CPU1_SA_CB<6>
  VSS88  = GND
  CB7_A  = M_C_CPU1_SA_CB<7>
  VSS89  = GND
  RESET_N  = M_C_CPU1_RESET_N
  VSS90  = GND
  CS1_A_N  = M_C_CPU1_SA_CS_N<1>
  VSS91  = GND
  CA1_A  = M_C_CPU1_SA_CA<1>
  VSS92  = GND
  CA3_A  = M_C_CPU1_SA_CA<3>
  VSS93  = GND
  CA5_A  = M_C_CPU1_SA_CA<5>
  VSS94  = GND
  CK_T  = M_C_CPU1_CLK_DP<0>
  CK_C  = M_C_CPU1_CLK_DN<0>
  VSS95  = GND
  RFU4  = NC
  CA1_B  = M_C_CPU1_SB_CA<1>
  VSS96  = GND
  CA3_B  = M_C_CPU1_SB_CA<3>
  VSS97  = GND
  CA5_B  = M_C_CPU1_SB_CA<5>
  VSS98  = GND
  PAR_B  = M_C_CPU1_SB_PAR
  VSS99  = GND
  CS1_B_N  = M_C_CPU1_SB_CS_N<1>
  VSS100  = GND
  RFU5  = NC
  RFU6  = NC
  VSS101  = GND
  CB6_B  = M_C_CPU1_SB_CB<6>
  VSS102  = GND
  CB7_B  = M_C_CPU1_SB_CB<7>
  VSS103  = GND
  DQS4_B_C  = M_C_CPU1_SB_DQS_DN<4>
  DQS4_B_T  = M_C_CPU1_SB_DQS_DP<4>
  VSS104  = GND
  CB2_B  = M_C_CPU1_SB_CB<2>
  VSS105  = GND
  CB3_B  = M_C_CPU1_SB_CB<3>
  VSS106  = GND
  DQ2_B  = M_C_CPU1_SB_DQ<2>
  VSS107  = GND
  DQ3_B  = M_C_CPU1_SB_DQ<3>
  VSS108  = GND
  \dqs5_b_c||tdqs5_b_c\  = M_C_CPU1_SB_DQS_DN<5>
  \dqs5_b_t||tdqs5_b_t\  = M_C_CPU1_SB_DQS_DP<5>
  VSS109  = GND
  DQ6_B  = M_C_CPU1_SB_DQ<6>
  VSS110  = GND
  DQ7_B  = M_C_CPU1_SB_DQ<7>
  VSS111  = GND
  DQ10_B  = M_C_CPU1_SB_DQ<10>
  VSS112  = GND
  DQ11_B  = M_C_CPU1_SB_DQ<11>
  VSS113  = GND
  \dqs6_b_c||tdqs6_b_c\  = M_C_CPU1_SB_DQS_DN<6>
  \dqs6_b_t||tdqs6_b_t\  = M_C_CPU1_SB_DQS_DP<6>
  VSS114  = GND
  DQ14_B  = M_C_CPU1_SB_DQ<14>
  VSS115  = GND
  DQ15_B  = M_C_CPU1_SB_DQ<15>
  VSS116  = GND
  DQ18_B  = M_C_CPU1_SB_DQ<18>
  VSS117  = GND
  DQ19_B  = M_C_CPU1_SB_DQ<19>
  VSS118  = GND
  \dqs7_b_c||tdqs7_b_c\  = M_C_CPU1_SB_DQS_DN<7>
  \dqs7_b_t||tdqs7_b_t\  = M_C_CPU1_SB_DQS_DP<7>
  VSS119  = GND
  DQ22_B  = M_C_CPU1_SB_DQ<22>
  VSS120  = GND
  DQ23_B  = M_C_CPU1_SB_DQ<23>
  VSS121  = GND
  DQ26_B  = M_C_CPU1_SB_DQ<26>
  VSS122  = GND
  DQ27_B  = M_C_CPU1_SB_DQ<27>
  VSS123  = GND
  \dqs8_b_c||tdqs8_b_c\  = M_C_CPU1_SB_DQS_DN<8>
  \dqs8_b_t||tdqs8_b_t\  = M_C_CPU1_SB_DQS_DP<8>
  VSS124  = GND
  DQ30_B  = M_C_CPU1_SB_DQ<30>
  VSS125  = GND
  DQ31_B  = M_C_CPU1_SB_DQ<31>
  VSS126  = GND
  G1  = GND
  G2  = GND
  G3  = GND

(kicad_pcb
	(version 20260206)
	(generator "pcbnew")
	(generator_version "10.0")
	(general
		(thickness 1.6)
		(legacy_teardrops no)
	)
	(paper "A4")
	(title_block
		(title "04192023_DAF0TMB3IC0_F0TG_MB_C_brd_V02_OCP.brd")
		(comment 1 "Grand Teton / footprint 4188 of 8354 (J28), pads 231-276 of 291")
	)
	(layers
		(0 "F.Cu" signal "TOP")
		(4 "In1.Cu" signal "GND")
		(6 "In2.Cu" signal "IN1")
		(8 "In3.Cu" signal "GND1")
		(10 "In4.Cu" signal "IN2")
		(12 "In5.Cu" signal "GND2")
		(14 "In6.Cu" signal "IN3")
		(16 "In7.Cu" signal "GND3")
		(18 "In8.Cu" signal "VCC")
		(20 "In9.Cu" signal "VCC1")
		(22 "In10.Cu" signal "GND4")
		(24 "In11.Cu" signal "IN4")
		(26 "In12.Cu" signal "GND5")
		(28 "In13.Cu" signal "IN5")
		(30 "In14.Cu" signal "GND6")
		(32 "In15.Cu" signal "IN6")
		(34 "In16.Cu" signal "GND7")
		(2 "B.Cu" signal "BOTTOM")
		(9 "F.Adhes" user "F.Adhesive")
		(11 "B.Adhes" user "B.Adhesive")
		(13 "F.Paste" user "Package Geometry/Pastemask Top")
		(15 "B.Paste" user "Package Geometry/Pastemask Bottom")
		(5 "F.SilkS" user "Ref Des/Silkscreen Top")
		(7 "B.SilkS" user "Ref Des/Silkscreen Bottom")
		(1 "F.Mask" user "Board Geometry/Soldermask Top")
		(3 "B.Mask" user "Board Geometry/Soldermask Bottom")
		(17 "Dwgs.User" user "User.Drawings")
		(19 "Cmts.User" user "User.Comments")
		(21 "Eco1.User" user "User.Eco1")
		(23 "Eco2.User" user "User.Eco2")
		(25 "Edge.Cuts" user "Board Geometry/Outline")
		(27 "Margin" user)
		(31 "F.CrtYd" user "Package Geometry/Place Bound Top")
		(29 "B.CrtYd" user "Package Geometry/Place Bound Bottom")
		(35 "F.Fab" user "Ref Des/Assembly Top")
		(33 "B.Fab" user "Ref Des/Assembly Bottom")
	)
	(footprint ""
		(layer "F.Cu")
		(at 42.289984 -255.560322 180)
		(property "Reference" "J28"
			(at -2.876296 -82.230976 0)
			(unlocked yes)
			(layer "F.SilkS")
			(effects
				(font
					(size 0.7874 0.5842)
					(thickness 0.1524)
				)
			)
		)
		(property "Value" ""
			(at 0 0 180)
			(layer "F.Fab")
			(effects
				(font
					(size 1.27 1.27)
				)
			)
		)
		(duplicate_pad_numbers_are_jumpers no)
		(pad "231" smd rect
			(at 2.050034 14.875002 90)
			(size 0.519938 1.4986)
			(layers "F.Cu" "F.Mask" "F.Paste")
			(net "Net_2289")
		)
		(pad "232" smd rect
			(at 2.050034 15.724886 90)
			(size 0.519938 1.4986)
			(layers "F.Cu" "F.Mask" "F.Paste")
			(net "Net_2290")
		)
		(pad "233" smd rect
			(at 2.050034 16.575024 90)
			(size 0.519938 1.4986)
			(layers "F.Cu" "F.Mask" "F.Paste")
			(net "GND")
		)
		(pad "234" smd rect
			(at 2.050034 17.424908 90)
			(size 0.519938 1.4986)
			(layers "F.Cu" "F.Mask" "F.Paste")
			(net "M_C_CPU1_SB_CB<6>")
		)
		(pad "235" smd rect
			(at 2.050034 18.275046 90)
			(size 0.519938 1.4986)
			(layers "F.Cu" "F.Mask" "F.Paste")
			(net "GND")
		)
		(pad "236" smd rect
			(at 2.050034 19.12493 90)
			(size 0.519938 1.4986)
			(layers "F.Cu" "F.Mask" "F.Paste")
			(net "M_C_CPU1_SB_CB<7>")
		)
		(pad "237" smd rect
			(at 2.050034 19.975068 90)
			(size 0.519938 1.4986)
			(layers "F.Cu" "F.Mask" "F.Paste")
			(net "GND")
		)
		(pad "238" smd rect
			(at 2.050034 20.824952 90)
			(size 0.519938 1.4986)
			(layers "F.Cu" "F.Mask" "F.Paste")
			(net "M_C_CPU1_SB_DQS_DN<4>")
		)
		(pad "239" smd rect
			(at 2.050034 21.67509 90)
			(size 0.519938 1.4986)
			(layers "F.Cu" "F.Mask" "F.Paste")
			(net "M_C_CPU1_SB_DQS_DP<4>")
		)
		(pad "240" smd rect
			(at 2.050034 22.524974 90)
			(size 0.519938 1.4986)
			(layers "F.Cu" "F.Mask" "F.Paste")
			(net "GND")
		)
		(pad "241" smd rect
			(at 2.050034 23.375112 90)
			(size 0.519938 1.4986)
			(layers "F.Cu" "F.Mask" "F.Paste")
			(net "M_C_CPU1_SB_CB<2>")
		)
		(pad "242" smd rect
			(at 2.050034 24.224996 90)
			(size 0.519938 1.4986)
			(layers "F.Cu" "F.Mask" "F.Paste")
			(net "GND")
		)
		(pad "243" smd rect
			(at 2.050034 25.07488 90)
			(size 0.519938 1.4986)
			(layers "F.Cu" "F.Mask" "F.Paste")
			(net "M_C_CPU1_SB_CB<3>")
		)
		(pad "244" smd rect
			(at 2.050034 25.925018 90)
			(size 0.519938 1.4986)
			(layers "F.Cu" "F.Mask" "F.Paste")
			(net "GND")
		)
		(pad "245" smd rect
			(at 2.050034 26.774902 90)
			(size 0.519938 1.4986)
			(layers "F.Cu" "F.Mask" "F.Paste")
			(net "M_C_CPU1_SB_DQ<2>")
		)
		(pad "246" smd rect
			(at 2.050034 27.62504 90)
			(size 0.519938 1.4986)
			(layers "F.Cu" "F.Mask" "F.Paste")
			(net "GND")
		)
		(pad "247" smd rect
			(at 2.050034 28.474924 90)
			(size 0.519938 1.4986)
			(layers "F.Cu" "F.Mask" "F.Paste")
			(net "M_C_CPU1_SB_DQ<3>")
		)
		(pad "248" smd rect
			(at 2.050034 29.325062 90)
			(size 0.519938 1.4986)
			(layers "F.Cu" "F.Mask" "F.Paste")
			(net "GND")
		)
		(pad "249" smd rect
			(at 2.050034 30.174946 90)
			(size 0.519938 1.4986)
			(layers "F.Cu" "F.Mask" "F.Paste")
			(net "M_C_CPU1_SB_DQS_DN<5>")
		)
		(pad "250" smd rect
			(at 2.050034 31.025084 90)
			(size 0.519938 1.4986)
			(layers "F.Cu" "F.Mask" "F.Paste")
			(net "M_C_CPU1_SB_DQS_DP<5>")
		)
		(pad "251" smd rect
			(at 2.050034 31.874968 90)
			(size 0.519938 1.4986)
			(layers "F.Cu" "F.Mask" "F.Paste")
			(net "GND")
		)
		(pad "252" smd rect
			(at 2.050034 32.725106 90)
			(size 0.519938 1.4986)
			(layers "F.Cu" "F.Mask" "F.Paste")
			(net "M_C_CPU1_SB_DQ<6>")
		)
		(pad "253" smd rect
			(at 2.050034 33.57499 90)
			(size 0.519938 1.4986)
			(layers "F.Cu" "F.Mask" "F.Paste")
			(net "GND")
		)
		(pad "254" smd rect
			(at 2.050034 34.425128 90)
			(size 0.519938 1.4986)
			(layers "F.Cu" "F.Mask" "F.Paste")
			(net "M_C_CPU1_SB_DQ<7>")
		)
		(pad "255" smd rect
			(at 2.050034 35.275012 90)
			(size 0.519938 1.4986)
			(layers "F.Cu" "F.Mask" "F.Paste")
			(net "GND")
		)
		(pad "256" smd rect
			(at 2.050034 36.124896 90)
			(size 0.519938 1.4986)
			(layers "F.Cu" "F.Mask" "F.Paste")
			(net "M_C_CPU1_SB_DQ<10>")
		)
		(pad "257" smd rect
			(at 2.050034 36.975034 90)
			(size 0.519938 1.4986)
			(layers "F.Cu" "F.Mask" "F.Paste")
			(net "GND")
		)
		(pad "258" smd rect
			(at 2.050034 37.824918 90)
			(size 0.519938 1.4986)
			(layers "F.Cu" "F.Mask" "F.Paste")
			(net "M_C_CPU1_SB_DQ<11>")
		)
		(pad "259" smd rect
			(at 2.050034 38.675056 90)
			(size 0.519938 1.4986)
			(layers "F.Cu" "F.Mask" "F.Paste")
			(net "GND")
		)
		(pad "260" smd rect
			(at 2.050034 39.52494 90)
			(size 0.519938 1.4986)
			(layers "F.Cu" "F.Mask" "F.Paste")
			(net "M_C_CPU1_SB_DQS_DN<6>")
		)
		(pad "261" smd rect
			(at 2.050034 40.375078 90)
			(size 0.519938 1.4986)
			(layers "F.Cu" "F.Mask" "F.Paste")
			(net "M_C_CPU1_SB_DQS_DP<6>")
		)
		(pad "262" smd rect
			(at 2.050034 41.224962 90)
			(size 0.519938 1.4986)
			(layers "F.Cu" "F.Mask" "F.Paste")
			(net "GND")
		)
		(pad "263" smd rect
			(at 2.050034 42.0751 90)
			(size 0.519938 1.4986)
			(layers "F.Cu" "F.Mask" "F.Paste")
			(net "M_C_CPU1_SB_DQ<14>")
		)
		(pad "264" smd rect
			(at 2.050034 42.924984 90)
			(size 0.519938 1.4986)
			(layers "F.Cu" "F.Mask" "F.Paste")
			(net "GND")
		)
		(pad "265" smd rect
			(at 2.050034 43.775122 90)
			(size 0.519938 1.4986)
			(layers "F.Cu" "F.Mask" "F.Paste")
			(net "M_C_CPU1_SB_DQ<15>")
		)
		(pad "266" smd rect
			(at 2.050034 44.625006 90)
			(size 0.519938 1.4986)
			(layers "F.Cu" "F.Mask" "F.Paste")
			(net "GND")
		)
		(pad "267" smd rect
			(at 2.050034 45.47489 90)
			(size 0.519938 1.4986)
			(layers "F.Cu" "F.Mask" "F.Paste")
			(net "M_C_CPU1_SB_DQ<18>")
		)
		(pad "268" smd rect
			(at 2.050034 46.325028 90)
			(size 0.519938 1.4986)
			(layers "F.Cu" "F.Mask" "F.Paste")
			(net "GND")
		)
		(pad "269" smd rect
			(at 2.050034 47.174912 90)
			(size 0.519938 1.4986)
			(layers "F.Cu" "F.Mask" "F.Paste")
			(net "M_C_CPU1_SB_DQ<19>")
		)
		(pad "270" smd rect
			(at 2.050034 48.02505 90)
			(size 0.519938 1.4986)
			(layers "F.Cu" "F.Mask" "F.Paste")
			(net "GND")
		)
		(pad "271" smd rect
			(at 2.050034 48.874934 90)
			(size 0.519938 1.4986)
			(layers "F.Cu" "F.Mask" "F.Paste")
			(net "M_C_CPU1_SB_DQS_DN<7>")
		)
		(pad "272" smd rect
			(at 2.050034 49.725072 90)
			(size 0.519938 1.4986)
			(layers "F.Cu" "F.Mask" "F.Paste")
			(net "M_C_CPU1_SB_DQS_DP<7>")
		)
		(pad "273" smd rect
			(at 2.050034 50.574956 90)
			(size 0.519938 1.4986)
			(layers "F.Cu" "F.Mask" "F.Paste")
			(net "GND")
		)
		(pad "274" smd rect
			(at 2.050034 51.425094 90)
			(size 0.519938 1.4986)
			(layers "F.Cu" "F.Mask" "F.Paste")
			(net "M_C_CPU1_SB_DQ<22>")
		)
		(pad "275" smd rect
			(at 2.050034 52.274978 90)
			(size 0.519938 1.4986)
			(layers "F.Cu" "F.Mask" "F.Paste")
			(net "GND")
		)
		(pad "276" smd rect
			(at 2.050034 53.125116 90)
			(size 0.519938 1.4986)
			(layers "F.Cu" "F.Mask" "F.Paste")
			(net "M_C_CPU1_SB_DQ<23>")
		)
	)
)
